FILE_TYPE = CONNECTIVITY;
{Allegro Design Entry HDL 17.2-2016 S081 (4005846) 1/11/2022}
"PAGE_NUMBER" = 28;
0"NC";
1"P5V_AUX\g";
2"P5V_USB_REAR\g";
3"P3V3_AUX\g";
4"P3V3_AUX\g";
5"P3V3_AUX\g";
6"P3V3_AUX\g";
7"GND\g";
8"GND\g";
9"GND\g";
10"P3V3_AUX\g";
11"P3V3_AUX\g";
12"GND\g";
13"P3V3_AUX\g";
14"P3V3_AUX\g";
15"GND\g";
16"GND\g";
17"P5V_AUX\g";
18"P3V3_AUX\g";
19"P3V3_AUX\g";
20"P3V3_AUX\g";
21"GND\g";
22"GND\g";
23"GND\g";
24"P5V_AUX\g";
25"GND\g";
26"GND\g";
27"GND\g";
28"GND\g";
29"USB_OC0_REAR_R_N";
30"USB_OC0_REAR_N";
31"SMB_DEBUG_AUX_LVC3_USB_R1_SDA";
32"SMB_DEBUG_AUX_LVC3_USB_R1_SCL";
33"SMB_BMC_MM15_R1_SDA";
34"SMB_BMC_MM15_R1_SCL";
35"USB_OC0_ILIM";
36"LED_POSTCODE_INT";
37"USB_OC0_EN";
38"SMB_DEBUG_AUX_LVC3_USB_R3_SDA";
39"SMB_DEBUG_AUX_LVC3_USB_R3_SCL";
40"SMB_DEBUG_AUX_LVC3_USB_SCL";
41"FM_SLPS3_GF_R2_N";
42"FM_CPU_MSMI_CATERR_LVT3_R3_N";
43"PWRGD_PSU_AC_PWROK";
44"FM_CPU_MSMI_CATERR_LVT3_N";
45"FM_SLPS3_GF_N";
46"PWRGD_DSW_PWROK";
47"RST_PLTRST_N";
48"PWRGD_SYS_PWROK";
49"FM_UART_SEL_N";
50"FM_SOL_UART_CH_SEL_R3";
51"FM_SOL_UART_CH_SEL";
52"DEBUG_PORT_PRSNT_BUF_EN";
53"SMB_DEBUG_AUX_LVC3_USB_SCL";
54"SMB_DEBUG_AUX_LVC3_USB_SDA";
55"DEBUG_PORT_PRSNT";
56"PWRGD_SYS_PWROK_R1";
57"RST_PLTRST_R2_N";
58"PWRGD_DSW_PWROK_R3";
59"FM_UART_SWITCH_N";
60"FM_UART_SWITCH_N";
61"DEBUG_PORT_PRSNT_BUF_EN";
62"DEBUG_PORT_PRSNT_BUF_R_EN";
63"LED_POSTCODE_A2";
64"LED_POSTCODE_A0";
65"LED_POSTCODE_A1";
66"SMB_BMC_MM15_SDA";
67"SMB_DEBUG_AUX_LVC3_USB_SDA";
68"LED_POSTCODE_0_R1";
69"LED_POSTCODE_6_R1";
70"LED_POSTCODE_7_R1";
71"FM_DEBUG_RST_BTN_N";
72"LED_POSTCODE_1_R1";
73"LED_POSTCODE_A1";
74"LED_POSTCODE_A0";
75"SMB_BMC_MM15_SCL";
76"LED_POSTCODE_2_R1";
77"LED_POSTCODE_3_R1";
78"LED_POSTCODE_4_R1";
79"LED_POSTCODE_5_R1";
80"FM_DEBUG_PWR_BTN_N";
81"LED_POSTCODE_A2";
%"UNIVERSAL_GND"
"1","(200,1825)","2","logical_power","I100";
;
HDL_POWER"GND"
CDS_LIB"logical_power";
"A"23;
%"Q_CAP"
"1","(-75,2825)","2","pure_quanta","I101";
;
MATERIAL"X7R"
VALUE"0.1UF"
VOLTAGE"25V"
PACK_TYPE"0402"
TOLERANCE"10%"
PART_NUMBER"CH4104K1B00"
CDS_LIB"pure_quanta"
LOCATION"C158"
$SEC"1"
CDS_SEC"1";
"B"
$PN"2"7;
"A"
$PN"1"20;
%"UNIVERSAL_GND"
"1","(-75,2550)","0","logical_power","I102";
;
HDL_POWER"GND"
CDS_LIB"logical_power";
"A"7;
%"Q_RES"
"1","(-150,3375)","0","pure_quanta","I104";
;
WATTAGE"1/16W"
MATERIAL"CHIP"
TOLERANCE"5%"
VALUE"0"
PART_NUMBER"CS00002JB13"
PACK_TYPE"0402LF"
CDS_LIB"pure_quanta"
LOCATION"R670"
$SEC"1"
CDS_SEC"1";
"B"
$PN"2"61;
"A"
$PN"1"62;
%"Q_RES"
"2","(-950,3075)","2","pure_quanta","I105";
;
MATERIAL"EMPTY"
WATTAGE"1/16W"
PACK_TYPE"0402LF"
VALUE"100K"
PART_NUMBER"CS41002FB09"
TOLERANCE"1%"
CDS_LIB"pure_quanta"
LOCATION"R296"
$SEC"1"
CDS_SEC"1";
"A"
$PN"1"62;
"B"
$PN"2"8;
%"UNIVERSAL_GND"
"1","(-950,2725)","2","logical_power","I106";
;
HDL_POWER"GND"
CDS_LIB"logical_power";
"A"8;
%"UNIVERSAL_POWER"
"1","(-1350,4025)","0","logical_power","I107";
;
HDL_POWER"P3V3_AUX"
CDS_LIB"logical_power";
"A"10;
%"Q_RES"
"1","(-1125,2125)","0","pure_quanta","I108";
;
VALUE"0"
MATERIAL"CHIP"
CDS_LIB"pure_quanta"
TOLERANCE"5%"
WATTAGE"1/16W"
PACK_TYPE"0402LF"
PART_NUMBER"CS00002JB13"
LOCATION"R294"
$SEC"1"
CDS_SEC"1";
"B"
$PN"2"33;
"A"
$PN"1"66;
%"Q_RES"
"1","(-1125,2225)","0","pure_quanta","I109";
;
MATERIAL"CHIP"
PART_NUMBER"CS00002JB13"
VALUE"0"
CDS_LIB"pure_quanta"
TOLERANCE"5%"
WATTAGE"1/16W"
PACK_TYPE"0402LF"
LOCATION"R135"
$SEC"1"
CDS_SEC"1";
"B"
$PN"2"34;
"A"
$PN"1"75;
%"VCCAUX15"
"1","(-2125,4075)","0","logical_power","I110";
;
HDL_POWER"P3V3_AUX"
CDS_LIB"logical_power";
"A"11;
%"Q_RES"
"2","(-1350,3800)","0","pure_quanta","I113";
;
PART_NUMBER"CS31002FB08"
PACK_TYPE"0402LF"
TOLERANCE"1%"
WATTAGE"1/16W"
MATERIAL"CHIP"
VALUE"10K"
CDS_LIB"pure_quanta"
LOCATION"R295"
$SEC"1"
CDS_SEC"1";
"A"
$PN"1"10;
"B"
$PN"2"62;
%"UNIVERSAL_GND"
"1","(-2900,3100)","2","logical_power","I115";
;
HDL_POWER"GND"
CDS_LIB"logical_power";
"A"12;
%"Q_RES"
"1","(2000,-1125)","2","pure_quanta","I125";
;
VALUE"0"
TOLERANCE"5%"
PACK_TYPE"0402LF"
MATERIAL"CHIP"
WATTAGE"1/16W"
CDS_LIB"pure_quanta"
PART_NUMBER"CS00002JB13"
LOCATION"R701"
$SEC"1"
CDS_SEC"1";
"B"
$PN"2"56;
"A"
$PN"1"48;
%"Q_RES"
"1","(2000,-1175)","2","pure_quanta","I126";
;
VALUE"0"
TOLERANCE"5%"
PACK_TYPE"0402LF"
MATERIAL"CHIP"
WATTAGE"1/16W"
CDS_LIB"pure_quanta"
PART_NUMBER"CS00002JB13"
LOCATION"R702"
$SEC"1"
CDS_SEC"1";
"B"
$PN"2"57;
"A"
$PN"1"47;
%"Q_RES"
"1","(2000,-1225)","2","pure_quanta","I127";
;
VALUE"0"
TOLERANCE"5%"
PACK_TYPE"0402LF"
MATERIAL"CHIP"
WATTAGE"1/16W"
CDS_LIB"pure_quanta"
PART_NUMBER"CS00002JB13"
LOCATION"R703"
$SEC"1"
CDS_SEC"1";
"B"
$PN"2"58;
"A"
$PN"1"46;
%"Q_RES"
"1","(2000,-1300)","2","pure_quanta","I128";
;
VALUE"0"
TOLERANCE"5%"
MATERIAL"EMPTY"
PACK_TYPE"0402LF"
WATTAGE"1/16W"
CDS_LIB"pure_quanta"
PART_NUMBER"CS00002JB13"
LOCATION"R719"
$SEC"1"
CDS_SEC"1";
"B"
$PN"2"58;
"A"
$PN"1"43;
%"UNIVERSAL_GND"
"1","(-1150,-675)","5","logical_power","I140";
;
CDS_LIB"logical_power"
HDL_POWER"GND";
"A"27;
%"PCA9555PW"
"1","(-425,-975)","0","pure_quanta","I141";
;
PART_NUMBER"TMP_QAL009555K04"
PACK_TYPE"SMLF"
MATERIAL"IC"
VALUE"PCA9555PW"
SEC_TYPE"SMLF"
NEEDS_NO_SIZE"TRUE"
CDS_LIB"pure_quanta"
LOCATION"U40"
SEC"1";
"VDD"
$PN"24"3;
"VSS"
$PN"12"27;
"INT*"
$PN"1"36;
"SDA"
$PN"23"38;
"SCL"
$PN"22"39;
"P00"
$PN"4"68;
"P01"
$PN"5"72;
"P02"
$PN"6"76;
"P03"
$PN"7"77;
"P04"
$PN"8"78;
"P05"
$PN"9"79;
"P06"
$PN"10"69;
"P07"
$PN"11"70;
"P10"
$PN"13"71;
"P11"
$PN"14"80;
"P12"
$PN"15"56;
"P13"
$PN"16"57;
"P14"
$PN"17"58;
"P15"
$PN"18"42;
"P16"
$PN"19"41;
"P17"
$PN"20"60;
"A0"
$PN"21"74;
"A1"
$PN"2"73;
"A2"
$PN"3"81;
%"Q_RES"
"1","(2000,-1625)","2","pure_quanta","I144";
;
VALUE"0"
TOLERANCE"5%"
PACK_TYPE"0402LF"
WATTAGE"1/16W"
MATERIAL"CHIP"
CDS_LIB"pure_quanta"
PART_NUMBER"CS00002JB13"
LOCATION"R720"
$SEC"1"
CDS_SEC"1";
"B"
$PN"2"42;
"A"
$PN"1"44;
%"Q_RES"
"1","(2025,-1825)","2","pure_quanta","I145";
;
VALUE"0"
TOLERANCE"5%"
WATTAGE"1/16W"
PACK_TYPE"0402LF"
MATERIAL"CHIP"
CDS_LIB"pure_quanta"
PART_NUMBER"CS00002JB13"
LOCATION"R721"
$SEC"1"
CDS_SEC"1";
"B"
$PN"2"41;
"A"
$PN"1"45;
%"Q_CAP"
"1","(-1475,-300)","0","pure_quanta","I146";
;
VALUE"0.1UF"
PACK_TYPE"0402"
PART_NUMBER"CH4104K1B00"
MATERIAL"X7R"
TOLERANCE"10%"
VOLTAGE"25V"
CDS_LIB"pure_quanta"
LOCATION"C300"
$SEC"1"
CDS_SEC"1";
"B"
$PN"2"26;
"A"
$PN"1"3;
%"Q_RES"
"2","(-1775,-325)","2","pure_quanta","I147";
;
TOLERANCE"1%"
MATERIAL"CHIP"
PACK_TYPE"0402LF"
VALUE"4.7K"
PART_NUMBER"CS24702FB06"
WATTAGE"1/16W"
CDS_LIB"pure_quanta"
LOCATION"R667"
$SEC"1"
CDS_SEC"1";
"A"
$PN"1"4;
"B"
$PN"2"36;
%"UNIVERSAL_GND"
"1","(-1475,-550)","0","logical_power","I148";
;
CDS_LIB"logical_power"
HDL_POWER"GND";
"A"26;
%"Q_RES"
"1","(-2400,-1225)","0","pure_quanta","I152";
;
TOLERANCE"5%"
MATERIAL"CHIP"
VALUE"0"
WATTAGE"1/16W"
PACK_TYPE"0402LF"
CDS_LIB"pure_quanta"
PART_NUMBER"CS00002JB13"
LOCATION"R95"
$SEC"1"
CDS_SEC"1";
"B"
$PN"2"38;
"A"
$PN"1"67;
%"Q_RES"
"1","(-2400,-1325)","0","pure_quanta","I153";
;
VALUE"0"
WATTAGE"1/16W"
MATERIAL"CHIP"
PACK_TYPE"0402LF"
TOLERANCE"5%"
CDS_LIB"pure_quanta"
PART_NUMBER"CS00002JB13"
LOCATION"R632"
$SEC"1"
CDS_SEC"1";
"B"
$PN"2"39;
"A"
$PN"1"40;
%"UNIVERSAL_POWER"
"1","(-1150,-25)","0","logical_power","I154";
;
HDL_POWER"P3V3_AUX"
CDS_LIB"logical_power";
"A"3;
%"UNIVERSAL_POWER"
"1","(-1775,0)","0","logical_power","I155";
;
HDL_POWER"P3V3_AUX"
CDS_LIB"logical_power";
"A"4;
%"UNIVERSAL_GND"
"1","(4650,-1175)","0","logical_power","I159";
;
CDS_LIB"logical_power"
HDL_POWER"GND";
"A"25;
%"UNIVERSAL_POWER"
"1","(2725,1025)","0","logical_power","I160";
;
HDL_POWER"P3V3_AUX"
CDS_LIB"logical_power";
"A"14;
%"Q_RES"
"1","(3800,300)","2","pure_quanta","I161";
;
VALUE"0"
TOLERANCE"5%"
MATERIAL"CHIP"
WATTAGE"1/16W"
PACK_TYPE"0402LF"
CDS_LIB"pure_quanta"
PART_NUMBER"CS00002JB13"
LOCATION"R626"
$SEC"1"
CDS_SEC"1";
"B"
$PN"2"50;
"A"
$PN"1"51;
%"Q_RES"
"2","(2725,700)","0","pure_quanta","I162";
;
TOLERANCE"1%"
WATTAGE"1/16W"
MATERIAL"CHIP"
PACK_TYPE"0402LF"
VALUE"1K"
PART_NUMBER"CS21002FB06"
CDS_LIB"pure_quanta"
LOCATION"R736"
$SEC"1"
CDS_SEC"1";
"A"
$PN"1"14;
"B"
$PN"2"50;
%"2N7002A7"
"1","(4050,-625)","0","pure_quanta","I163";
;
MATERIAL"IC"
PART_TYPE"SMLF"
VALUE"2N7002A-7"
PART_NUMBER"BAM70020068"
CDS_LMAN_SYM_OUTLINE"-300,325,300,-325"
NEEDS_NO_SIZE"TRUE"
CDS_LIB"pure_quanta"
LOCATION"Q8"
$SEC"1"
CDS_SEC"1";
"S"
$PN"S"25;
"D"
$PN"D"50;
"G"
$PN"G"49;
%"Q_RES"
"1","(2725,-600)","2","pure_quanta","I164";
;
VALUE"0"
TOLERANCE"5%"
WATTAGE"1/16W"
MATERIAL"CHIP"
PACK_TYPE"0402LF"
CDS_LIB"pure_quanta"
PART_NUMBER"CS00002JB13"
LOCATION"R83"
$SEC"1"
CDS_SEC"1";
"B"
$PN"2"59;
"A"
$PN"1"49;
%"UNIVERSAL_POWER"
"1","(2475,175)","0","logical_power","I165";
;
HDL_POWER"P3V3_AUX"
CDS_LIB"logical_power";
"A"5;
%"Q_RES"
"2","(2475,-150)","2","pure_quanta","I166";
;
MATERIAL"CHIP"
PACK_TYPE"0402LF"
PART_NUMBER"CS21002FB06"
VALUE"1K"
TOLERANCE"1%"
WATTAGE"1/16W"
CDS_LIB"pure_quanta"
LOCATION"R735"
$SEC"1"
CDS_SEC"1";
"A"
$PN"1"5;
"B"
$PN"2"59;
%"Q_RES"
"2","(-3250,875)","0","pure_quanta","I168";
;
WATTAGE"1/16W"
MATERIAL"CHIP"
VALUE"4.7K"
TOLERANCE"1%"
PACK_TYPE"0402LF"
PART_NUMBER"CS24702FB06"
CDS_LIB"pure_quanta"
SEC_TYPE"0402LF"
LOCATION"R740"
SEC"1";
"A"
$PN"1"13;
"B"
$PN"2"63;
%"Q_RES"
"2","(-3600,875)","0","pure_quanta","I169";
;
MATERIAL"CHIP"
PACK_TYPE"0402LF"
WATTAGE"1/16W"
VALUE"4.7K"
TOLERANCE"1%"
CDS_LIB"pure_quanta"
SEC_TYPE"0402LF"
PART_NUMBER"CS24702FB06"
LOCATION"R739"
SEC"1";
"A"
$PN"1"13;
"B"
$PN"2"65;
%"UNIVERSAL_POWER"
"1","(-3950,1350)","0","logical_power","I170";
;
HDL_POWER"P3V3_AUX"
CDS_LIB"logical_power";
"A"13;
%"Q_RES"
"2","(-3950,875)","0","pure_quanta","I171";
;
VALUE"4.7K"
WATTAGE"1/16W"
PACK_TYPE"0402LF"
TOLERANCE"1%"
MATERIAL"CHIP"
CDS_LIB"pure_quanta"
SEC_TYPE"0402LF"
PART_NUMBER"CS24702FB06"
LOCATION"R738"
SEC"1";
"A"
$PN"1"13;
"B"
$PN"2"64;
%"Q_RES"
"2","(-3250,200)","0","pure_quanta","I172";
;
MATERIAL"EMPTY"
VALUE"100"
WATTAGE"1/16W"
PACK_TYPE"0402LF"
PART_NUMBER"CS11002FB07"
TOLERANCE"1%"
CDS_LIB"pure_quanta"
LOCATION"R745"
$SEC"1"
CDS_SEC"1";
"A"
$PN"1"63;
"B"
$PN"2"28;
%"Q_RES"
"2","(-3600,200)","0","pure_quanta","I173";
;
MATERIAL"EMPTY"
WATTAGE"1/16W"
VALUE"100"
TOLERANCE"1%"
PACK_TYPE"0402LF"
CDS_LIB"pure_quanta"
PART_NUMBER"CS11002FB07"
LOCATION"R744"
$SEC"1"
CDS_SEC"1";
"A"
$PN"1"65;
"B"
$PN"2"28;
%"UNIVERSAL_GND"
"1","(-3800,-275)","0","logical_power","I174";
;
CDS_LIB"logical_power"
HDL_POWER"GND";
"A"28;
%"Q_RES"
"2","(-3950,200)","0","pure_quanta","I175";
;
VALUE"100"
MATERIAL"EMPTY"
TOLERANCE"1%"
WATTAGE"1/16W"
PACK_TYPE"0402LF"
CDS_LIB"pure_quanta"
PART_NUMBER"CS11002FB07"
LOCATION"R743"
$SEC"1"
CDS_SEC"1";
"A"
$PN"1"64;
"B"
$PN"2"28;
%"NCP380HSNAJAAT1G"
"1","(-50,1250)","0","pure_quanta","I179";
;
PART_TYPE"SMLF"
VALUE"NCP380HSNAJAAT1G"
PART_NUMBER"AL000380K00"
MATERIAL"IC"
CDS_LIB"pure_quanta"
NEEDS_NO_SIZE"TRUE"
CDS_LMAN_SYM_OUTLINE"-225,100,225,-100"
SEC_TYPE""
LOCATION"U10"
SEC"1";
"GND"
$PN"2"9;
"EN"
$PN"3"37;
"OUT"
$PN"6"2;
"ILIM"
$PN"5"35;
"IN"
$PN"1"17;
"FLAG_N \B"
$PN"4"30;
%"74LVC1G07W57"
"1","(-2450,3475)","0","pure_quanta","I180";
;
PART_NUMBER"ALVC1G07001"
PART_TYPE"SMLF"
VALUE"74LVC1G07W5-7"
MATERIAL"IC"
CDS_LIB"pure_quanta"
NEEDS_NO_SIZE"TRUE"
CDS_LMAN_SYM_OUTLINE"-125,150,125,-150"
LOCATION"U23"
$SEC"1"
CDS_SEC"1";
"NC1"
$PN"1"0;
"Y"
$PN"4"62;
"GND"
$PN"3"12;
"A"
$PN"2"55;
"VCC"
$PN"5"11;
%"Q_CAP"
"1","(-1975,3700)","0","pure_quanta","I181";
;
MATERIAL"X7R"
PART_NUMBER"CH4104K1B00"
PACK_TYPE"0402"
TOLERANCE"10%"
VALUE"0.1UF"
VOLTAGE"25V"
CDS_LIB"pure_quanta"
LOCATION"C157"
$SEC"1"
CDS_SEC"1";
"B"
$PN"2"21;
"A"
$PN"1"11;
%"UNIVERSAL_GND"
"1","(-1975,3500)","0","logical_power","I182";
;
HDL_POWER"GND"
CDS_LIB"logical_power";
"A"21;
%"Q_RES"
"1","(3275,2225)","0","pure_quanta","I183";
;
MATERIAL"CHIP"
VALUE"33.2"
PACK_TYPE"0402LF"
WATTAGE"1/16W"
PART_NUMBER"CS03322FB03"
TOLERANCE"1%"
CDS_LIB"pure_quanta"
LOCATION"R300"
$SEC"1"
CDS_SEC"1";
"B"
$PN"2"53;
"A"
$PN"1"32;
%"Q_RES"
"1","(3275,2125)","0","pure_quanta","I184";
;
MATERIAL"CHIP"
VALUE"33.2"
PACK_TYPE"0402LF"
WATTAGE"1/16W"
PART_NUMBER"CS03322FB03"
TOLERANCE"1%"
CDS_LIB"pure_quanta"
LOCATION"R302"
$SEC"1"
CDS_SEC"1";
"B"
$PN"2"54;
"A"
$PN"1"31;
%"Q_RES"
"1","(1250,1250)","0","pure_quanta","I185";
;
VALUE"100"
PART_NUMBER"CS11002FB07"
MATERIAL"CHIP"
WATTAGE"1/16W"
TOLERANCE"1%"
PACK_TYPE"0402LF"
CDS_LIB"pure_quanta"
LOCATION"R384"
$SEC"1"
CDS_SEC"1";
"B"
$PN"2"29;
"A"
$PN"1"30;
%"Q_CAP"
"1","(1400,600)","0","pure_quanta","I35";
;
VALUE"470PF"
VOLTAGE"50V"
TOLERANCE"10%"
MATERIAL"X7R"
PACK_TYPE"0402"
PART_NUMBER"TMP_QCH14706KB18"
CDS_LIB"pure_quanta"
LOCATION"C172"
$SEC"1"
CDS_SEC"1";
"B"
$PN"2"22;
"A"
$PN"1"1;
%"UNIVERSAL_GND"
"1","(1400,275)","0","logical_power","I36";
;
HDL_POWER"GND"
CDS_LIB"logical_power";
"A"22;
%"UNIVERSAL_POWER"
"1","(800,875)","0","logical_power","I37";
;
HDL_POWER"P5V_AUX"
CDS_LIB"logical_power";
"A"1;
%"Q_CAP"
"1","(800,600)","0","pure_quanta","I38";
;
PART_NUMBER"CH6222MEA00"
PACK_TYPE"C0805"
MATERIAL"X6S"
TOLERANCE"20%"
VOLTAGE"10V"
VALUE"22UF"
CDS_LIB"pure_quanta"
LOCATION"C171"
$SEC"1"
CDS_SEC"1";
"B"
$PN"2"22;
"A"
$PN"1"1;
%"UNIVERSAL_POWER"
"1","(950,1700)","0","logical_power","I40";
;
HDL_POWER"P3V3_AUX"
CDS_LIB"logical_power";
"A"18;
%"Q_RES"
"2","(950,1525)","0","pure_quanta","I42";
;
PACK_TYPE"0402LF"
PART_NUMBER"CS31002FB08"
MATERIAL"CHIP"
VALUE"10K"
WATTAGE"1/16W"
TOLERANCE"1%"
CDS_LIB"pure_quanta"
LOCATION"R383"
$SEC"1"
CDS_SEC"1";
"A"
$PN"1"18;
"B"
$PN"2"30;
%"UNIVERSAL_POWER"
"1","(625,1475)","0","logical_power","I50";
;
HDL_POWER"P5V_USB_REAR"
CDS_LIB"logical_power";
"A"2;
%"UNIVERSAL_POWER"
"1","(-550,1475)","0","logical_power","I52";
;
HDL_POWER"P5V_AUX"
CDS_LIB"logical_power";
"A"17;
%"UNIVERSAL_GND"
"1","(-850,650)","0","logical_power","I53";
;
HDL_POWER"GND"
CDS_LIB"logical_power";
"A"9;
%"Q_RES"
"2","(-1000,1000)","0","pure_quanta","I54";
;
VALUE"20K"
TOLERANCE"1%"
WATTAGE"1/16W"
MATERIAL"CHIP"
PART_NUMBER"CS32002FB06"
PACK_TYPE"0402LF"
CDS_LIB"pure_quanta"
LOCATION"R378"
$SEC"1"
CDS_SEC"1";
"A"
$PN"1"35;
"B"
$PN"2"9;
%"UNIVERSAL_POWER"
"1","(-1200,1600)","0","logical_power","I61";
;
HDL_POWER"P5V_AUX"
CDS_LIB"logical_power";
"A"24;
%"Q_RES"
"2","(-1200,1400)","2","pure_quanta","I62";
;
PART_NUMBER"CS24702FB06"
WATTAGE"1/16W"
TOLERANCE"1%"
VALUE"4.7K"
MATERIAL"CHIP"
PACK_TYPE"0402LF"
CDS_LIB"pure_quanta"
LOCATION"R376"
$SEC"1"
CDS_SEC"1";
"A"
$PN"1"24;
"B"
$PN"2"37;
%"Q_RES"
"2","(-1200,925)","2","pure_quanta","I63";
;
WATTAGE"1/16W"
VALUE"10K"
MATERIAL"EMPTY"
TOLERANCE"1%"
PACK_TYPE"0402LF"
PART_NUMBER"CS31002FB08"
CDS_LIB"pure_quanta"
LOCATION"R377"
$SEC"1"
CDS_SEC"1";
"A"
$PN"1"37;
"B"
$PN"2"15;
%"UNIVERSAL_GND"
"1","(-1200,650)","0","logical_power","I64";
;
HDL_POWER"GND"
CDS_LIB"logical_power";
"A"15;
%"VCCAUX15"
"1","(1650,3225)","0","logical_power","I87";
;
HDL_POWER"P3V3_AUX"
CDS_LIB"logical_power";
"A"19;
%"VCCAUX15"
"1","(200,3075)","0","logical_power","I88";
;
HDL_POWER"P3V3_AUX"
CDS_LIB"logical_power";
"A"20;
%"Q_RES"
"2","(3050,2675)","0","pure_quanta","I91";
;
VALUE"4.7K"
MATERIAL"CHIP"
TOLERANCE"1%"
WATTAGE"1/16W"
PACK_TYPE"0402LF"
PART_NUMBER"CS24702FB06"
CDS_LIB"pure_quanta"
LOCATION"R299"
$SEC"1"
CDS_SEC"1";
"A"
$PN"1"6;
"B"
$PN"2"31;
%"VCCAUX15"
"1","(2500,3275)","0","logical_power","I95";
;
HDL_POWER"P3V3_AUX"
CDS_LIB"logical_power";
"A"6;
%"Q_RES"
"2","(2500,2675)","0","pure_quanta","I96";
;
PART_NUMBER"CS24702FB06"
PACK_TYPE"0402LF"
VALUE"4.7K"
TOLERANCE"1%"
WATTAGE"1/16W"
MATERIAL"CHIP"
CDS_LIB"pure_quanta"
LOCATION"R298"
$SEC"1"
CDS_SEC"1";
"A"
$PN"1"6;
"B"
$PN"2"32;
%"UNIVERSAL_GND"
"1","(1400,2675)","0","logical_power","I97";
;
HDL_POWER"GND"
CDS_LIB"logical_power";
"A"16;
%"Q_CAP"
"1","(1400,2925)","2","pure_quanta","I98";
;
MATERIAL"X7R"
TOLERANCE"10%"
VALUE"0.1UF"
VOLTAGE"25V"
PACK_TYPE"0402"
PART_NUMBER"CH4104K1B00"
CDS_LIB"pure_quanta"
LOCATION"C159"
$SEC"1"
CDS_SEC"1";
"B"
$PN"2"16;
"A"
$PN"1"19;
%"PCA9517ADP"
"1","(825,2175)","0","pure_quanta","I99";
;
VALUE"PCA9517ADP"
PACK_TYPE"SMLF"
MATERIAL"IC"
PART_NUMBER"AL009517K00"
NEEDS_NO_SIZE"TRUE"
CDS_LIB"pure_quanta"
LOCATION"U37"
$SEC"1"
CDS_SEC"1";
"SCLA"
$PN"2"34;
"ENABLE"
$PN"5"52;
"VCCA"
$PN"1"20;
"VCCB"
$PN"8"19;
"SDAA"
$PN"3"33;
"SDAB"
$PN"6"31;
"SCLB"
$PN"7"32;
"GND"
$PN"4"23;
END.
